(kicad_pcb
	(version 20221018)
	(generator pcbnew)
	(general
    (thickness 1.7403)
  )
	(paper "A4")
	(title_block
    (title "Data Center RDIMM DDR4 Tester")
    (date "2024-09-30")
    (rev "1.2.4")
		(comment 9 "footprints 92-100 of 690")
	)
	(layers
    (0 "F.Cu" signal)
    (1 "In1.Cu" power)
    (2 "In2.Cu" signal)
    (3 "In3.Cu" power)
    (4 "In4.Cu" power)
    (5 "In5.Cu" signal)
    (6 "In6.Cu" power)
    (7 "In7.Cu" signal)
    (8 "In8.Cu" power)
    (9 "In9.Cu" signal)
    (10 "In10.Cu" power)
    (31 "B.Cu" signal)
    (32 "B.Adhes" user "B.Adhesive")
    (33 "F.Adhes" user "F.Adhesive")
    (34 "B.Paste" user)
    (35 "F.Paste" user)
    (36 "B.SilkS" user "B.Silkscreen")
    (37 "F.SilkS" user "F.Silkscreen")
    (38 "B.Mask" user)
    (39 "F.Mask" user)
    (40 "Dwgs.User" user "User.Drawings")
    (41 "Cmts.User" user "User.Comments")
    (42 "Eco1.User" user "User.Eco1")
    (43 "Eco2.User" user "User.Eco2")
    (44 "Edge.Cuts" user)
    (45 "Margin" user)
    (46 "B.CrtYd" user "B.Courtyard")
    (47 "F.CrtYd" user "F.Courtyard")
    (48 "B.Fab" user)
    (49 "F.Fab" user)
  )
	(footprint "data-center-rdimm-ddr4-tester-footprints:antmicro-logo_scaled_20mm_mask"
		(layer "F.Cu")
    (at 222.05 103.65)
    (descr "Antmicro Logo scaled 20mm F.Mask")
    (tags "Antmicro Logo scaled 20mm F.Mask")
    (property "Author" "Antmicro")
    (property "License" "Apache-2.0")
    (property "MPN" "")
    (property "Manufacturer" "")
    (property "Sheetfile" "data-center-rdimm-ddr4-tester.kicad_sch")
    (property "Sheetname" "")
    (attr through_hole exclude_from_pos_files)
    (fp_text reference "N2" (at 0.05 -5.5) (layer "F.SilkS") hide
        (effects (font (size 0.7 0.7) (thickness 0.15)) (justify left bottom))
    )
    (fp_text value "antmicro_logo" (at -0.101 5.099) (layer "F.SilkS") hide
        (effects (font (size 0.7 0.7) (thickness 0.15)) (justify left bottom))
    )
  )
	(footprint "data-center-rdimm-ddr4-tester-footprints:C_1206_3216Metric" (layer "F.Cu")
    (at 111.7 102.647157)
    (descr "Capacitor SMD 1206")
    (tags "capacitor SMD 1206")
    (property "Author" "Antmicro")
    (property "Dielectric" "")
    (property "License" "Apache-2.0")
    (property "MPN" "C3216X5R1C476M160AB")
    (property "Manufacturer" "TDK")
    (property "Sheetfile" "supply.kicad_sch")
    (property "Sheetname" "Supply")
    (property "Val" "47u/16V")
    (property "Voltage" "")
    (property "ki_description" " ")
    (attr smd)
    (fp_text reference "C116" (at -2.756328 1.462843 90) (layer "F.SilkS")
        (effects (font (size 0.7 0.7) (thickness 0.15)) (justify left bottom))
    )
    (fp_text value "C_47u_16V_1206" (at 0 2.1) (layer "F.Fab") hide
        (effects (font (size 0.7 0.7) (thickness 0.15)) (justify left bottom))
    )
    (fp_text user "Author: Antmicro" (at -2.8 5.6) (layer "F.Fab") hide
        (effects (font (size 0.7 0.7) (thickness 0.15)) (justify left bottom))
    )
    (fp_text user "License: Apache-2.0" (at -2.8 6.6) (layer "F.Fab") hide
        (effects (font (size 0.7 0.7) (thickness 0.15)) (justify left bottom))
    )
    (fp_text user "${REFERENCE}" (at -2.8 4.6) (layer "F.Fab") hide
        (effects (font (size 0.7 0.7) (thickness 0.15)) (justify left bottom))
    )
    (fp_line (start -2.625 -0.3) (end -2.625 0.3)
      (stroke (width 0.15) (type solid)) (layer "F.SilkS"))
    (fp_line (start 0.5 -0.9) (end -0.5 -0.9)
      (stroke (width 0.15) (type solid)) (layer "F.SilkS"))
    (fp_line (start 0.5 0.9) (end -0.5 0.9)
      (stroke (width 0.15) (type solid)) (layer "F.SilkS"))
    (fp_line (start 2.625 -0.3) (end 2.625 0.3)
      (stroke (width 0.15) (type solid)) (layer "F.SilkS"))
    (fp_rect (start -2.8 -1.15) (end 2.8 1.15)
      (stroke (width 0.05) (type solid)) (fill none) (layer "F.CrtYd"))
    (fp_rect (start -1.6 -0.8) (end 1.6 0.8)
      (stroke (width 0.15) (type solid)) (fill none) (layer "F.Fab"))
    (pad "1" smd rect (at -1.8 0) (size 1.5 1.8) (layers "F.Cu" "F.Paste" "F.Mask")
      (net 103 "VIN") (pintype "passive"))
    (pad "2" smd rect (at 1.8 0) (size 1.5 1.8) (layers "F.Cu" "F.Paste" "F.Mask")
      (net 9 "GND") (pintype "passive"))
  )
	(footprint "data-center-rdimm-ddr4-tester-footprints:C_1206_3216Metric" (layer "F.Cu")
    (at 111.7 100.147157)
    (descr "Capacitor SMD 1206")
    (tags "capacitor SMD 1206")
    (property "Author" "Antmicro")
    (property "Dielectric" "")
    (property "License" "Apache-2.0")
    (property "MPN" "C3216X5R1C476M160AB")
    (property "Manufacturer" "TDK")
    (property "Sheetfile" "supply.kicad_sch")
    (property "Sheetname" "Supply")
    (property "Val" "47u/16V")
    (property "Voltage" "")
    (property "ki_description" " ")
    (attr smd)
    (fp_text reference "C117" (at -2.766328 1.302843 90) (layer "F.SilkS")
        (effects (font (size 0.7 0.7) (thickness 0.15)) (justify left bottom))
    )
    (fp_text value "C_47u_16V_1206" (at 0 2.1) (layer "F.Fab") hide
        (effects (font (size 0.7 0.7) (thickness 0.15)) (justify left bottom))
    )
    (fp_text user "License: Apache-2.0" (at -2.8 6.6) (layer "F.Fab") hide
        (effects (font (size 0.7 0.7) (thickness 0.15)) (justify left bottom))
    )
    (fp_text user "${REFERENCE}" (at -2.8 4.6) (layer "F.Fab") hide
        (effects (font (size 0.7 0.7) (thickness 0.15)) (justify left bottom))
    )
    (fp_text user "Author: Antmicro" (at -2.8 5.6) (layer "F.Fab") hide
        (effects (font (size 0.7 0.7) (thickness 0.15)) (justify left bottom))
    )
    (fp_line (start -2.625 -0.3) (end -2.625 0.3)
      (stroke (width 0.15) (type solid)) (layer "F.SilkS"))
    (fp_line (start 0.5 -0.9) (end -0.5 -0.9)
      (stroke (width 0.15) (type solid)) (layer "F.SilkS"))
    (fp_line (start 0.5 0.9) (end -0.5 0.9)
      (stroke (width 0.15) (type solid)) (layer "F.SilkS"))
    (fp_line (start 2.625 -0.3) (end 2.625 0.3)
      (stroke (width 0.15) (type solid)) (layer "F.SilkS"))
    (fp_rect (start -2.8 -1.15) (end 2.8 1.15)
      (stroke (width 0.05) (type solid)) (fill none) (layer "F.CrtYd"))
    (fp_rect (start -1.6 -0.8) (end 1.6 0.8)
      (stroke (width 0.15) (type solid)) (fill none) (layer "F.Fab"))
    (pad "1" smd rect (at -1.8 0) (size 1.5 1.8) (layers "F.Cu" "F.Paste" "F.Mask")
      (net 103 "VIN") (pintype "passive"))
    (pad "2" smd rect (at 1.8 0) (size 1.5 1.8) (layers "F.Cu" "F.Paste" "F.Mask")
      (net 9 "GND") (pintype "passive"))
  )
	(footprint "data-center-rdimm-ddr4-tester-footprints:C_1206_3216Metric" (layer "F.Cu")
    (at 111.7 105.147157)
    (descr "Capacitor SMD 1206")
    (tags "capacitor SMD 1206")
    (property "Author" "Antmicro")
    (property "Dielectric" "")
    (property "License" "Apache-2.0")
    (property "MPN" "C3216X5R1C476M160AB")
    (property "Manufacturer" "TDK")
    (property "Sheetfile" "supply.kicad_sch")
    (property "Sheetname" "Supply")
    (property "Val" "47u/16V")
    (property "Voltage" "")
    (property "ki_description" " ")
    (attr smd)
    (fp_text reference "C118" (at -2.76 1.652843 90) (layer "F.SilkS")
        (effects (font (size 0.7 0.7) (thickness 0.15)) (justify left bottom))
    )
    (fp_text value "C_47u_16V_1206" (at 0 2.1) (layer "F.Fab") hide
        (effects (font (size 0.7 0.7) (thickness 0.15)) (justify left bottom))
    )
    (fp_text user "${REFERENCE}" (at -2.8 4.6) (layer "F.Fab") hide
        (effects (font (size 0.7 0.7) (thickness 0.15)) (justify left bottom))
    )
    (fp_text user "Author: Antmicro" (at -2.8 5.6) (layer "F.Fab") hide
        (effects (font (size 0.7 0.7) (thickness 0.15)) (justify left bottom))
    )
    (fp_text user "License: Apache-2.0" (at -2.8 6.6) (layer "F.Fab") hide
        (effects (font (size 0.7 0.7) (thickness 0.15)) (justify left bottom))
    )
    (fp_line (start -2.625 -0.3) (end -2.625 0.3)
      (stroke (width 0.15) (type solid)) (layer "F.SilkS"))
    (fp_line (start 0.5 -0.9) (end -0.5 -0.9)
      (stroke (width 0.15) (type solid)) (layer "F.SilkS"))
    (fp_line (start 0.5 0.9) (end -0.5 0.9)
      (stroke (width 0.15) (type solid)) (layer "F.SilkS"))
    (fp_line (start 2.625 -0.3) (end 2.625 0.3)
      (stroke (width 0.15) (type solid)) (layer "F.SilkS"))
    (fp_rect (start -2.8 -1.15) (end 2.8 1.15)
      (stroke (width 0.05) (type solid)) (fill none) (layer "F.CrtYd"))
    (fp_rect (start -1.6 -0.8) (end 1.6 0.8)
      (stroke (width 0.15) (type solid)) (fill none) (layer "F.Fab"))
    (pad "1" smd rect (at -1.8 0) (size 1.5 1.8) (layers "F.Cu" "F.Paste" "F.Mask")
      (net 103 "VIN") (pintype "passive"))
    (pad "2" smd rect (at 1.8 0) (size 1.5 1.8) (layers "F.Cu" "F.Paste" "F.Mask")
      (net 9 "GND") (pintype "passive"))
  )
	(footprint "data-center-rdimm-ddr4-tester-footprints:PowerDI5" (layer "F.Cu")
    (at 110.9 122.3 90)
    (property "Author" "Antmicro")
    (property "License" "Apache-2.0")
    (property "MPN" "PDS760-13")
    (property "Manufacturer" "Diodes Incorporated")
    (property "Sheetfile" "supply.kicad_sch")
    (property "Sheetname" "Supply")
    (property "ki_description" "PDS760 Series 60 V 7 A Surface Mount Schottky Barrier Rectifier - PowerDI-5")
    (property "ki_keywords" "PDS760 Series 60 V 7 A Surface Mount Schottky Barrier Rectifier - PowerDI-5")
    (attr smd)
    (fp_text reference "D11" (at -3.78 -3.73 180) (layer "F.SilkS")
        (effects (font (size 0.7 0.7) (thickness 0.15)) (justify left bottom))
    )
    (fp_text value "PDS760" (at 0 3.4 90) (layer "F.Fab") hide
        (effects (font (size 0.7 0.7) (thickness 0.15)) (justify right bottom))
    )
    (fp_text user "License: Apache-2.0" (at -3.302 20.928 90) (layer "F.Fab") hide
        (effects (font (size 0.7 0.7) (thickness 0.15)) (justify left bottom))
    )
    (fp_text user "${REFERENCE}" (at -3.302 18.527 90) (layer "F.Fab") hide
        (effects (font (size 0.7 0.7) (thickness 0.15)) (justify left bottom))
    )
    (fp_text user "Author: Antmicro" (at -3.302 19.728 90) (layer "F.Fab") hide
        (effects (font (size 0.7 0.7) (thickness 0.15)) (justify left bottom))
    )
    (fp_line (start -2.7 -2) (end 2.7 -2)
      (stroke (width 0.12) (type solid)) (layer "F.SilkS"))
    (fp_line (start -2.7 -1.8) (end -2.7 -2)
      (stroke (width 0.12) (type solid)) (layer "F.SilkS"))
    (fp_line (start -2.7 2.023) (end -2.7 1.823)
      (stroke (width 0.12) (type solid)) (layer "F.SilkS"))
    (fp_line (start 2.7 -2) (end 2.7 -1.8)
      (stroke (width 0.12) (type solid)) (layer "F.SilkS"))
    (fp_line (start 2.7 1.823) (end 2.7 2.023)
      (stroke (width 0.12) (type solid)) (layer "F.SilkS"))
    (fp_line (start 2.7 2.023) (end -2.7 2.023)
      (stroke (width 0.12) (type solid)) (layer "F.SilkS"))
    (fp_rect (start -3.702 -2.3) (end 3.7 2.3)
      (stroke (width 0.05) (type solid)) (fill none) (layer "F.CrtYd"))
    (pad "A" smd roundrect (at -2.862 -0.94 180) (size 1.39 1.4) (layers "F.Cu" "F.Paste" "F.Mask") (roundrect_rratio 0.25)
      (net 626 "VIN_RAW") (pinfunction "A") (pintype "passive"))
    (pad "A" smd roundrect (at -2.862 0.941) (size 1.39 1.4) (layers "F.Cu" "F.Paste" "F.Mask") (roundrect_rratio 0.25)
      (net 626 "VIN_RAW") (pinfunction "A") (pintype "passive"))
    (pad "C" smd roundrect (at 1.1 0) (size 3.36 4.86) (layers "F.Cu" "F.Paste" "F.Mask") (roundrect_rratio 0.05)
      (net 103 "VIN") (pinfunction "C") (pintype "passive"))
  )
	(footprint "data-center-rdimm-ddr4-tester-footprints:R_0402_1005Metric" (layer "F.Cu")
    (at 235.767 117.001)
    (descr "Resistor SMD 0402")
    (tags "resistor SMD 0402")
    (property "Author" "Antmicro")
    (property "Current" "1A")
    (property "License" "Apache-2.0")
    (property "MPN" "ERJ2GE0R00X")
    (property "Manufacturer" "Panasonic")
    (property "Sheetfile" "config-spi.kicad_sch")
    (property "Sheetname" "Config SPI flash")
    (property "Tolerance" "")
    (property "Val" "0R")
    (property "ki_description" "0R resistor in 0402 package with unspecified tolerance")
    (attr smd)
    (fp_text reference "R26" (at -1.017 -3.641) (layer "F.SilkS")
        (effects (font (size 0.7 0.7) (thickness 0.15)) (justify left bottom))
    )
    (fp_text value "R_0R_0402" (at 0 1.4) (layer "F.Fab") hide
        (effects (font (size 0.7 0.7) (thickness 0.15)) (justify left bottom))
    )
    (fp_text user "${REFERENCE}" (at -0.95 3.168) (layer "F.Fab") hide
        (effects (font (size 0.7 0.7) (thickness 0.15)) (justify left bottom))
    )
    (fp_text user "License: Apache-2.0" (at -0.95 5.169) (layer "F.Fab") hide
        (effects (font (size 0.7 0.7) (thickness 0.15)) (justify left bottom))
    )
    (fp_text user "Author: Antmicro" (at -0.95 4.169) (layer "F.Fab") hide
        (effects (font (size 0.7 0.7) (thickness 0.15)) (justify left bottom))
    )
    (fp_rect (start -0.93 -0.47) (end 0.93 0.47)
      (stroke (width 0.05) (type solid)) (fill none) (layer "F.CrtYd"))
    (fp_rect (start -0.5 -0.25) (end 0.5 0.25)
      (stroke (width 0.15) (type solid)) (fill none) (layer "F.Fab"))
    (pad "1" smd roundrect (at -0.485 0) (size 0.59 0.64) (layers "F.Cu" "F.Paste" "F.Mask") (roundrect_rratio 0.25)
      (net 599 "Net-(U3-~{HOLD}{slash}IO3)") (pintype "passive"))
    (pad "2" smd roundrect (at 0.485 0) (size 0.59 0.64) (layers "F.Cu" "F.Paste" "F.Mask") (roundrect_rratio 0.25)
      (net 22 "QSPI_DQ3") (pintype "passive"))
  )
	(footprint "data-center-rdimm-ddr4-tester-footprints:LED_0603_1608Metric_G" (layer "F.Cu")
    (at 243.15 126.36 -90)
    (descr "LED SMD 0603 Green")
    (tags "LED SMD 0603 Green")
    (property "Author" "Antmicro")
    (property "License" "Apache-2.0")
    (property "MPN" "KP-1608CGCK")
    (property "Manufacturer" "Kingbright")
    (property "Sheetfile" "supply.kicad_sch")
    (property "Sheetname" "Supply")
    (attr smd)
    (fp_text reference "PWR1" (at 3.05 -2.43 -90) (layer "F.SilkS")
        (effects (font (size 0.7 0.7) (thickness 0.15)) (justify left bottom))
    )
    (fp_text value "LED_G_0603_KP-1608CGCK" (at 0 1.6 -90) (layer "F.Fab") hide
        (effects (font (size 0.7 0.7) (thickness 0.15)) (justify left bottom))
    )
    (fp_text user "License: Apache-2.0" (at -1.31 5.769 -90) (layer "F.Fab") hide
        (effects (font (size 0.7 0.7) (thickness 0.15)) (justify left bottom))
    )
    (fp_text user "${REFERENCE}" (at -1.31 3.769 -90) (layer "F.Fab") hide
        (effects (font (size 0.7 0.7) (thickness 0.15)) (justify left bottom))
    )
    (fp_text user "Author: Antmicro" (at -1.31 4.769 -90) (layer "F.Fab") hide
        (effects (font (size 0.7 0.7) (thickness 0.15)) (justify left bottom))
    )
    (fp_line (start -0.27 -0.35) (end 0.27 -0.35)
      (stroke (width 0.15) (type solid)) (layer "F.SilkS"))
    (fp_line (start -0.27 0.351) (end 0.27 0.351)
      (stroke (width 0.15) (type solid)) (layer "F.SilkS"))
    (fp_line (start -0.106328 -0.200008) (end -0.106328 0.199992)
      (stroke (width 0.1) (type solid)) (layer "F.SilkS"))
    (fp_line (start -0.106328 -0.200008) (end 0.093672 -0.000008)
      (stroke (width 0.1) (type solid)) (layer "F.SilkS"))
    (fp_line (start -0.106328 -0.000008) (end -0.29 0)
      (stroke (width 0.1) (type solid)) (layer "F.SilkS"))
    (fp_line (start 0.093672 -0.200008) (end 0.093672 0.199992)
      (stroke (width 0.1) (type solid)) (layer "F.SilkS"))
    (fp_line (start 0.093672 -0.000008) (end -0.106328 0.199992)
      (stroke (width 0.1) (type solid)) (layer "F.SilkS"))
    (fp_line (start 0.093672 -0.000008) (end 0.293672 -0.000008)
      (stroke (width 0.1) (type solid)) (layer "F.SilkS"))
    (fp_line (start 1.25 0.32) (end 1.25 -0.32)
      (stroke (width 0.15) (type solid)) (layer "F.SilkS"))
    (fp_rect (start 1.26 0.65) (end -1.26 -0.65)
      (stroke (width 0.05) (type solid)) (fill none) (layer "F.CrtYd"))
    (fp_line (start -0.599 0) (end -0.201 0)
      (stroke (width 0.15) (type solid)) (layer "F.Fab"))
    (fp_line (start -0.201 -0.2) (end -0.201 0)
      (stroke (width 0.15) (type solid)) (layer "F.Fab"))
    (fp_line (start -0.201 0) (end -0.201 0.202)
      (stroke (width 0.15) (type solid)) (layer "F.Fab"))
    (fp_line (start -0.201 0.202) (end 0.101 0)
      (stroke (width 0.15) (type solid)) (layer "F.Fab"))
    (fp_line (start 0.101 0) (end -0.201 -0.2)
      (stroke (width 0.15) (type solid)) (layer "F.Fab"))
    (fp_line (start 0.199 -0.2) (end 0.199 -0.1)
      (stroke (width 0.15) (type solid)) (layer "F.Fab"))
    (fp_line (start 0.199 0) (end 0.597 0)
      (stroke (width 0.15) (type solid)) (layer "F.Fab"))
    (fp_line (start 0.199 0.202) (end 0.199 -0.1)
      (stroke (width 0.15) (type solid)) (layer "F.Fab"))
    (fp_rect (start -0.848 -0.4) (end 0.85 0.402)
      (stroke (width 0.15) (type solid)) (fill none) (layer "F.Fab"))
    (pad "1" smd rect (at -0.75 0 90) (size 0.8 0.8) (layers "F.Cu" "F.Paste" "F.Mask")
      (net 143 "3V3_SYS") (pinfunction "1") (pintype "passive"))
    (pad "2" smd rect (at 0.75 0 90) (size 0.8 0.8) (layers "F.Cu" "F.Paste" "F.Mask")
      (net 115 "Net-(PWR1-Pad2)") (pinfunction "2") (pintype "passive"))
  )
	(footprint "data-center-rdimm-ddr4-tester-footprints:C_0402_1005Metric" (layer "F.Cu")
    (at 151.086328 91.874306 180)
    (descr "Capacitor SMD 0402")
    (tags "capacitor SMD 0402")
    (property "Author" "Antmicro")
    (property "Dielectric" "")
    (property "License" "Apache-2.0")
    (property "MPN" "GRM155R61A475MEAAD")
    (property "Manufacturer" "Murata")
    (property "Sheetfile" "ethernet.kicad_sch")
    (property "Sheetname" "Ethernet")
    (property "Val" "4u7")
    (property "Voltage" "")
    (property "ki_description" " ")
    (attr smd)
    (fp_text reference "C119" (at 1.386328 1.594306 180) (layer "F.SilkS")
        (effects (font (size 0.7 0.7) (thickness 0.15)) (justify left bottom))
    )
    (fp_text value "C_4u7_0402" (at 0 1.4 180) (layer "F.Fab") hide
        (effects (font (size 0.7 0.7) (thickness 0.15)) (justify left bottom))
    )
    (fp_text user "License: Apache-2.0" (at -0.932 5.17 180) (layer "F.Fab") hide
        (effects (font (size 0.7 0.7) (thickness 0.15)) (justify left bottom))
    )
    (fp_text user "Author: Antmicro" (at -0.932 4.17 180) (layer "F.Fab") hide
        (effects (font (size 0.7 0.7) (thickness 0.15)) (justify left bottom))
    )
    (fp_text user "${REFERENCE}" (at -0.932 3.168 180) (layer "F.Fab") hide
        (effects (font (size 0.7 0.7) (thickness 0.15)) (justify left bottom))
    )
    (fp_rect (start -0.94 -0.47) (end 0.94 0.47)
      (stroke (width 0.05) (type solid)) (fill none) (layer "F.CrtYd"))
    (fp_rect (start -0.499 -0.249) (end 0.499 0.249)
      (stroke (width 0.15) (type solid)) (fill none) (layer "F.Fab"))
    (pad "1" smd roundrect (at -0.484 0 180) (size 0.59 0.64) (layers "F.Cu" "F.Paste" "F.Mask") (roundrect_rratio 0.25)
      (net 306 "1V2_SYS") (pintype "passive"))
    (pad "2" smd roundrect (at 0.484 0 180) (size 0.59 0.64) (layers "F.Cu" "F.Paste" "F.Mask") (roundrect_rratio 0.25)
      (net 9 "GND") (pintype "passive"))
  )
	(footprint "data-center-rdimm-ddr4-tester-footprints:C_0402_1005Metric" (layer "F.Cu")
    (at 151.086328 92.874306 180)
    (descr "Capacitor SMD 0402")
    (tags "capacitor SMD 0402")
    (property "Author" "Antmicro")
    (property "Dielectric" "")
    (property "License" "Apache-2.0")
    (property "MPN" "C1005X5R1E474M050BB")
    (property "Manufacturer" "TDK")
    (property "Sheetfile" "ethernet.kicad_sch")
    (property "Sheetname" "Ethernet")
    (property "Val" "470n")
    (property "Voltage" "")
    (property "ki_description" " ")
    (attr smd)
    (fp_text reference "C120" (at 1.386328 1.594306 180) (layer "F.SilkS")
        (effects (font (size 0.7 0.7) (thickness 0.15)) (justify left bottom))
    )
    (fp_text value "C_470n_0402" (at 0 1.4 180) (layer "F.Fab") hide
        (effects (font (size 0.7 0.7) (thickness 0.15)) (justify left bottom))
    )
    (fp_text user "Author: Antmicro" (at -0.932 4.17 180) (layer "F.Fab") hide
        (effects (font (size 0.7 0.7) (thickness 0.15)) (justify left bottom))
    )
    (fp_text user "License: Apache-2.0" (at -0.932 5.17 180) (layer "F.Fab") hide
        (effects (font (size 0.7 0.7) (thickness 0.15)) (justify left bottom))
    )
    (fp_text user "${REFERENCE}" (at -0.932 3.168 180) (layer "F.Fab") hide
        (effects (font (size 0.7 0.7) (thickness 0.15)) (justify left bottom))
    )
    (fp_rect (start -0.94 -0.47) (end 0.94 0.47)
      (stroke (width 0.05) (type solid)) (fill none) (layer "F.CrtYd"))
    (fp_rect (start -0.499 -0.249) (end 0.499 0.249)
      (stroke (width 0.15) (type solid)) (fill none) (layer "F.Fab"))
    (pad "1" smd roundrect (at -0.484 0 180) (size 0.59 0.64) (layers "F.Cu" "F.Paste" "F.Mask") (roundrect_rratio 0.25)
      (net 306 "1V2_SYS") (pintype "passive"))
    (pad "2" smd roundrect (at 0.484 0 180) (size 0.59 0.64) (layers "F.Cu" "F.Paste" "F.Mask") (roundrect_rratio 0.25)
      (net 9 "GND") (pintype "passive"))
  )
)
